(kicad_pcb
	(version 20260206)
	(generator "pcbnew")
	(generator_version "10.0")
	(general
		(thickness 1.6)
		(legacy_teardrops no)
	)
	(paper "A4")
	(title_block
		(title "04192023_DAF0TMB3IC0_F0TG_MB_C_brd_V02_OCP.brd")
		(comment 1 "Grand Teton / footprints 6940-6946 of 8354")
	)
	(layers
		(0 "F.Cu" signal "TOP")
		(4 "In1.Cu" signal "GND")
		(6 "In2.Cu" signal "IN1")
		(8 "In3.Cu" signal "GND1")
		(10 "In4.Cu" signal "IN2")
		(12 "In5.Cu" signal "GND2")
		(14 "In6.Cu" signal "IN3")
		(16 "In7.Cu" signal "GND3")
		(18 "In8.Cu" signal "VCC")
		(20 "In9.Cu" signal "VCC1")
		(22 "In10.Cu" signal "GND4")
		(24 "In11.Cu" signal "IN4")
		(26 "In12.Cu" signal "GND5")
		(28 "In13.Cu" signal "IN5")
		(30 "In14.Cu" signal "GND6")
		(32 "In15.Cu" signal "IN6")
		(34 "In16.Cu" signal "GND7")
		(2 "B.Cu" signal "BOTTOM")
		(9 "F.Adhes" user "F.Adhesive")
		(11 "B.Adhes" user "B.Adhesive")
		(13 "F.Paste" user "Package Geometry/Pastemask Top")
		(15 "B.Paste" user "Package Geometry/Pastemask Bottom")
		(5 "F.SilkS" user "Ref Des/Silkscreen Top")
		(7 "B.SilkS" user "Ref Des/Silkscreen Bottom")
		(1 "F.Mask" user "Board Geometry/Soldermask Top")
		(3 "B.Mask" user "Board Geometry/Soldermask Bottom")
		(17 "Dwgs.User" user "User.Drawings")
		(19 "Cmts.User" user "User.Comments")
		(21 "Eco1.User" user "User.Eco1")
		(23 "Eco2.User" user "User.Eco2")
		(25 "Edge.Cuts" user "Board Geometry/Outline")
		(27 "Margin" user)
		(31 "F.CrtYd" user "Package Geometry/Place Bound Top")
		(29 "B.CrtYd" user "Package Geometry/Place Bound Bottom")
		(35 "F.Fab" user "Ref Des/Assembly Top")
		(33 "B.Fab" user "Ref Des/Assembly Bottom")
	)
	(footprint ""
		(layer "B.Cu")
		(at 152.959054 -313.96305 90)
		(property "Reference" "R574"
			(at 0 0 90)
			(layer "B.SilkS")
			(hide yes)
			(effects
				(font
					(size 1.27 1.27)
				)
				(justify mirror)
			)
		)
		(property "Value" ""
			(at 0 0 90)
			(layer "B.Fab")
			(effects
				(font
					(size 1.27 1.27)
				)
				(justify mirror)
			)
		)
		(duplicate_pad_numbers_are_jumpers no)
		(fp_line
			(start 0.7874 -0.4064)
			(end -0.7874 -0.4064)
			(stroke
				(width 0.1524)
				(type default)
			)
			(layer "B.SilkS")
		)
		(fp_line
			(start -0.7874 -0.4064)
			(end -0.7874 0.4064)
			(stroke
				(width 0.1524)
				(type default)
			)
			(layer "B.SilkS")
		)
		(fp_line
			(start 0.7874 0.4064)
			(end 0.7874 -0.4064)
			(stroke
				(width 0.1524)
				(type default)
			)
			(layer "B.SilkS")
		)
		(fp_line
			(start -0.7874 0.4064)
			(end 0.7874 0.4064)
			(stroke
				(width 0.1524)
				(type default)
			)
			(layer "B.SilkS")
		)
		(fp_line
			(start 0.67945 -0.305054)
			(end 0.12065 -0.305054)
			(stroke
				(width 0.1)
				(type default)
			)
			(layer "B.Fab")
		)
		(fp_line
			(start 0.12065 -0.305054)
			(end 0.12065 -0.2794)
			(stroke
				(width 0.1)
				(type default)
			)
			(layer "B.Fab")
		)
		(fp_line
			(start -0.12065 -0.3048)
			(end -0.67945 -0.3048)
			(stroke
				(width 0.1)
				(type default)
			)
			(layer "B.Fab")
		)
		(fp_line
			(start -0.67945 -0.3048)
			(end -0.67945 0.3048)
			(stroke
				(width 0.1)
				(type default)
			)
			(layer "B.Fab")
		)
		(fp_line
			(start 0.12065 -0.2794)
			(end -0.12065 -0.2794)
			(stroke
				(width 0.1)
				(type default)
			)
			(layer "B.Fab")
		)
		(fp_line
			(start -0.12065 -0.2794)
			(end -0.12065 -0.3048)
			(stroke
				(width 0.1)
				(type default)
			)
			(layer "B.Fab")
		)
		(fp_line
			(start 0.12065 0.2794)
			(end 0.12065 0.3048)
			(stroke
				(width 0.1)
				(type default)
			)
			(layer "B.Fab")
		)
		(fp_line
			(start -0.120396 0.2794)
			(end 0.12065 0.2794)
			(stroke
				(width 0.1)
				(type default)
			)
			(layer "B.Fab")
		)
		(fp_line
			(start 0.67945 0.3048)
			(end 0.67945 -0.305054)
			(stroke
				(width 0.1)
				(type default)
			)
			(layer "B.Fab")
		)
		(fp_line
			(start 0.12065 0.3048)
			(end 0.67945 0.3048)
			(stroke
				(width 0.1)
				(type default)
			)
			(layer "B.Fab")
		)
		(fp_line
			(start -0.120396 0.3048)
			(end -0.120396 0.2794)
			(stroke
				(width 0.1)
				(type default)
			)
			(layer "B.Fab")
		)
		(fp_line
			(start -0.67945 0.3048)
			(end -0.120396 0.3048)
			(stroke
				(width 0.1)
				(type default)
			)
			(layer "B.Fab")
		)
		(pad "1" smd circle
			(at 0.40005 0 270)
			(size 0 0)
			(layers "B.Cu" "B.Mask" "B.Paste")
			(net "XTAL_CPU1_R_X32K_X1")
		)
		(pad "2" smd circle
			(at -0.40005 0 270)
			(size 0 0)
			(layers "B.Cu" "B.Mask" "B.Paste")
			(net "XTAL_CPU1_X32K_X1")
		)
	)
	(footprint ""
		(layer "B.Cu")
		(at 356.081838 -250.25731)
		(property "Reference" "C270"
			(at 0 0 0)
			(layer "B.SilkS")
			(hide yes)
			(effects
				(font
					(size 1.27 1.27)
				)
				(justify mirror)
			)
		)
		(property "Value" ""
			(at 0 0 0)
			(layer "B.Fab")
			(effects
				(font
					(size 1.27 1.27)
				)
				(justify mirror)
			)
		)
		(duplicate_pad_numbers_are_jumpers no)
		(fp_line
			(start -0.7874 -0.4064)
			(end -0.7874 0.4064)
			(stroke
				(width 0.1524)
				(type default)
			)
			(layer "B.SilkS")
		)
		(fp_line
			(start -0.7874 0.4064)
			(end 0.7874 0.4064)
			(stroke
				(width 0.1524)
				(type default)
			)
			(layer "B.SilkS")
		)
		(fp_line
			(start 0.7874 -0.4064)
			(end -0.7874 -0.4064)
			(stroke
				(width 0.1524)
				(type default)
			)
			(layer "B.SilkS")
		)
		(fp_line
			(start 0.7874 0.4064)
			(end 0.7874 -0.4064)
			(stroke
				(width 0.1524)
				(type default)
			)
			(layer "B.SilkS")
		)
		(fp_line
			(start -0.67945 -0.3048)
			(end -0.67945 0.3048)
			(stroke
				(width 0.1)
				(type default)
			)
			(layer "B.Fab")
		)
		(fp_line
			(start -0.67945 0.3048)
			(end -0.120396 0.3048)
			(stroke
				(width 0.1)
				(type default)
			)
			(layer "B.Fab")
		)
		(fp_line
			(start -0.12065 -0.3048)
			(end -0.67945 -0.3048)
			(stroke
				(width 0.1)
				(type default)
			)
			(layer "B.Fab")
		)
		(fp_line
			(start -0.12065 -0.2794)
			(end -0.12065 -0.3048)
			(stroke
				(width 0.1)
				(type default)
			)
			(layer "B.Fab")
		)
		(fp_line
			(start -0.120396 0.2794)
			(end 0.12065 0.2794)
			(stroke
				(width 0.1)
				(type default)
			)
			(layer "B.Fab")
		)
		(fp_line
			(start -0.120396 0.3048)
			(end -0.120396 0.2794)
			(stroke
				(width 0.1)
				(type default)
			)
			(layer "B.Fab")
		)
		(fp_line
			(start 0.12065 -0.305054)
			(end 0.12065 -0.2794)
			(stroke
				(width 0.1)
				(type default)
			)
			(layer "B.Fab")
		)
		(fp_line
			(start 0.12065 -0.2794)
			(end -0.12065 -0.2794)
			(stroke
				(width 0.1)
				(type default)
			)
			(layer "B.Fab")
		)
		(fp_line
			(start 0.12065 0.2794)
			(end 0.12065 0.3048)
			(stroke
				(width 0.1)
				(type default)
			)
			(layer "B.Fab")
		)
		(fp_line
			(start 0.12065 0.3048)
			(end 0.67945 0.3048)
			(stroke
				(width 0.1)
				(type default)
			)
			(layer "B.Fab")
		)
		(fp_line
			(start 0.67945 -0.305054)
			(end 0.12065 -0.305054)
			(stroke
				(width 0.1)
				(type default)
			)
			(layer "B.Fab")
		)
		(fp_line
			(start 0.67945 0.3048)
			(end 0.67945 -0.305054)
			(stroke
				(width 0.1)
				(type default)
			)
			(layer "B.Fab")
		)
		(pad "1" smd circle
			(at 0.40005 0 180)
			(size 0 0)
			(layers "B.Cu" "B.Mask" "B.Paste")
			(net "PVDDCR_CPU0_P0")
		)
		(pad "2" smd circle
			(at -0.40005 0 180)
			(size 0 0)
			(layers "B.Cu" "B.Mask" "B.Paste")
			(net "GND")
		)
	)
	(footprint ""
		(layer "B.Cu")
		(at 175.886364 -10.1473 -90)
		(property "Reference" "R2422"
			(at 0 0 90)
			(layer "B.SilkS")
			(hide yes)
			(effects
				(font
					(size 1.27 1.27)
				)
				(justify mirror)
			)
		)
		(property "Value" ""
			(at 0 0 90)
			(layer "B.Fab")
			(effects
				(font
					(size 1.27 1.27)
				)
				(justify mirror)
			)
		)
		(duplicate_pad_numbers_are_jumpers no)
		(fp_line
			(start -0.7874 0.4064)
			(end 0.7874 0.4064)
			(stroke
				(width 0.1524)
				(type default)
			)
			(layer "B.SilkS")
		)
		(fp_line
			(start 0.7874 0.4064)
			(end 0.7874 -0.4064)
			(stroke
				(width 0.1524)
				(type default)
			)
			(layer "B.SilkS")
		)
		(fp_line
			(start -0.7874 -0.4064)
			(end -0.7874 0.4064)
			(stroke
				(width 0.1524)
				(type default)
			)
			(layer "B.SilkS")
		)
		(fp_line
			(start 0.7874 -0.4064)
			(end -0.7874 -0.4064)
			(stroke
				(width 0.1524)
				(type default)
			)
			(layer "B.SilkS")
		)
		(fp_line
			(start -0.67945 0.3048)
			(end -0.120396 0.3048)
			(stroke
				(width 0.1)
				(type default)
			)
			(layer "B.Fab")
		)
		(fp_line
			(start -0.120396 0.3048)
			(end -0.120396 0.2794)
			(stroke
				(width 0.1)
				(type default)
			)
			(layer "B.Fab")
		)
		(fp_line
			(start 0.12065 0.3048)
			(end 0.67945 0.3048)
			(stroke
				(width 0.1)
				(type default)
			)
			(layer "B.Fab")
		)
		(fp_line
			(start 0.67945 0.3048)
			(end 0.67945 -0.305054)
			(stroke
				(width 0.1)
				(type default)
			)
			(layer "B.Fab")
		)
		(fp_line
			(start -0.120396 0.2794)
			(end 0.12065 0.2794)
			(stroke
				(width 0.1)
				(type default)
			)
			(layer "B.Fab")
		)
		(fp_line
			(start 0.12065 0.2794)
			(end 0.12065 0.3048)
			(stroke
				(width 0.1)
				(type default)
			)
			(layer "B.Fab")
		)
		(fp_line
			(start -0.12065 -0.2794)
			(end -0.12065 -0.3048)
			(stroke
				(width 0.1)
				(type default)
			)
			(layer "B.Fab")
		)
		(fp_line
			(start 0.12065 -0.2794)
			(end -0.12065 -0.2794)
			(stroke
				(width 0.1)
				(type default)
			)
			(layer "B.Fab")
		)
		(fp_line
			(start -0.67945 -0.3048)
			(end -0.67945 0.3048)
			(stroke
				(width 0.1)
				(type default)
			)
			(layer "B.Fab")
		)
		(fp_line
			(start -0.12065 -0.3048)
			(end -0.67945 -0.3048)
			(stroke
				(width 0.1)
				(type default)
			)
			(layer "B.Fab")
		)
		(fp_line
			(start 0.12065 -0.305054)
			(end 0.12065 -0.2794)
			(stroke
				(width 0.1)
				(type default)
			)
			(layer "B.Fab")
		)
		(fp_line
			(start 0.67945 -0.305054)
			(end 0.12065 -0.305054)
			(stroke
				(width 0.1)
				(type default)
			)
			(layer "B.Fab")
		)
		(pad "1" smd circle
			(at 0.40005 0 90)
			(size 0 0)
			(layers "B.Cu" "B.Mask" "B.Paste")
			(net "SMB_VR_SENSOR_3V3AUX_SDA")
		)
		(pad "2" smd circle
			(at -0.40005 0 90)
			(size 0 0)
			(layers "B.Cu" "B.Mask" "B.Paste")
			(net "SMB_VR_3V3AUX_SDA_R0")
		)
	)
	(footprint ""
		(layer "B.Cu")
		(at 299.265594 -393.48156 180)
		(property "Reference" "R983"
			(at 0 0 0)
			(layer "B.SilkS")
			(hide yes)
			(effects
				(font
					(size 1.27 1.27)
				)
				(justify mirror)
			)
		)
		(property "Value" ""
			(at 0 0 0)
			(layer "B.Fab")
			(effects
				(font
					(size 1.27 1.27)
				)
				(justify mirror)
			)
		)
		(duplicate_pad_numbers_are_jumpers no)
		(fp_line
			(start 0.32512 0.175006)
			(end 0.32512 -0.175006)
			(stroke
				(width 0.1)
				(type default)
			)
			(layer "B.Fab")
		)
		(fp_line
			(start 0.32512 -0.175006)
			(end -0.32512 -0.175006)
			(stroke
				(width 0.1)
				(type default)
			)
			(layer "B.Fab")
		)
		(fp_line
			(start -0.32512 0.175006)
			(end 0.32512 0.175006)
			(stroke
				(width 0.1)
				(type default)
			)
			(layer "B.Fab")
		)
		(fp_line
			(start -0.32512 -0.175006)
			(end -0.32512 0.175006)
			(stroke
				(width 0.1)
				(type default)
			)
			(layer "B.Fab")
		)
		(pad "1" smd rect
			(at 0.2667 0)
			(size 0.3048 0.381)
			(layers "B.Cu" "B.Mask" "B.Paste")
			(net "P1V8_CPU0_RT_1D")
		)
		(pad "2" smd rect
			(at -0.2667 0 180)
			(size 0.3048 0.381)
			(layers "B.Cu" "B.Mask" "B.Paste")
			(net "TEST1_RT_CPU0_P0")
		)
	)
	(footprint ""
		(layer "B.Cu")
		(at 318.99098 -398.942052 90)
		(property "Reference" "C586"
			(at 0 0 90)
			(layer "B.SilkS")
			(hide yes)
			(effects
				(font
					(size 1.27 1.27)
				)
				(justify mirror)
			)
		)
		(property "Value" ""
			(at 0 0 90)
			(layer "B.Fab")
			(effects
				(font
					(size 1.27 1.27)
				)
				(justify mirror)
			)
		)
		(duplicate_pad_numbers_are_jumpers no)
		(fp_line
			(start 0.7874 -0.4064)
			(end -0.7874 -0.4064)
			(stroke
				(width 0.1524)
				(type default)
			)
			(layer "B.SilkS")
		)
		(fp_line
			(start -0.7874 -0.4064)
			(end -0.7874 0.4064)
			(stroke
				(width 0.1524)
				(type default)
			)
			(layer "B.SilkS")
		)
		(fp_line
			(start 0.7874 0.4064)
			(end 0.7874 -0.4064)
			(stroke
				(width 0.1524)
				(type default)
			)
			(layer "B.SilkS")
		)
		(fp_line
			(start -0.7874 0.4064)
			(end 0.7874 0.4064)
			(stroke
				(width 0.1524)
				(type default)
			)
			(layer "B.SilkS")
		)
		(fp_line
			(start 0.67945 -0.305054)
			(end 0.12065 -0.305054)
			(stroke
				(width 0.1)
				(type default)
			)
			(layer "B.Fab")
		)
		(fp_line
			(start 0.12065 -0.305054)
			(end 0.12065 -0.2794)
			(stroke
				(width 0.1)
				(type default)
			)
			(layer "B.Fab")
		)
		(fp_line
			(start -0.12065 -0.3048)
			(end -0.67945 -0.3048)
			(stroke
				(width 0.1)
				(type default)
			)
			(layer "B.Fab")
		)
		(fp_line
			(start -0.67945 -0.3048)
			(end -0.67945 0.3048)
			(stroke
				(width 0.1)
				(type default)
			)
			(layer "B.Fab")
		)
		(fp_line
			(start 0.12065 -0.2794)
			(end -0.12065 -0.2794)
			(stroke
				(width 0.1)
				(type default)
			)
			(layer "B.Fab")
		)
		(fp_line
			(start -0.12065 -0.2794)
			(end -0.12065 -0.3048)
			(stroke
				(width 0.1)
				(type default)
			)
			(layer "B.Fab")
		)
		(fp_line
			(start 0.12065 0.2794)
			(end 0.12065 0.3048)
			(stroke
				(width 0.1)
				(type default)
			)
			(layer "B.Fab")
		)
		(fp_line
			(start -0.120396 0.2794)
			(end 0.12065 0.2794)
			(stroke
				(width 0.1)
				(type default)
			)
			(layer "B.Fab")
		)
		(fp_line
			(start 0.67945 0.3048)
			(end 0.67945 -0.305054)
			(stroke
				(width 0.1)
				(type default)
			)
			(layer "B.Fab")
		)
		(fp_line
			(start 0.12065 0.3048)
			(end 0.67945 0.3048)
			(stroke
				(width 0.1)
				(type default)
			)
			(layer "B.Fab")
		)
		(fp_line
			(start -0.120396 0.3048)
			(end -0.120396 0.2794)
			(stroke
				(width 0.1)
				(type default)
			)
			(layer "B.Fab")
		)
		(fp_line
			(start -0.67945 0.3048)
			(end -0.120396 0.3048)
			(stroke
				(width 0.1)
				(type default)
			)
			(layer "B.Fab")
		)
		(pad "1" smd circle
			(at 0.40005 0 270)
			(size 0 0)
			(layers "B.Cu" "B.Mask" "B.Paste")
			(net "P0V9_CPU0_RT0_2A")
		)
		(pad "2" smd circle
			(at -0.40005 0 270)
			(size 0 0)
			(layers "B.Cu" "B.Mask" "B.Paste")
			(net "GND")
		)
	)
	(footprint ""
		(layer "B.Cu")
		(at 89.560146 -182.607966 -90)
		(property "Reference" "PC265_2"
			(at 0 0 90)
			(layer "B.SilkS")
			(hide yes)
			(effects
				(font
					(size 1.27 1.27)
				)
				(justify mirror)
			)
		)
		(property "Value" ""
			(at 0 0 90)
			(layer "B.Fab")
			(effects
				(font
					(size 1.27 1.27)
				)
				(justify mirror)
			)
		)
		(duplicate_pad_numbers_are_jumpers no)
		(fp_line
			(start -1.524 0.762)
			(end 1.524 0.762)
			(stroke
				(width 0.1524)
				(type default)
			)
			(layer "B.SilkS")
		)
		(fp_line
			(start 1.524 0.762)
			(end 1.524 -0.762)
			(stroke
				(width 0.1524)
				(type default)
			)
			(layer "B.SilkS")
		)
		(fp_line
			(start -1.524 -0.762)
			(end -1.524 0.762)
			(stroke
				(width 0.1524)
				(type default)
			)
			(layer "B.SilkS")
		)
		(fp_line
			(start 1.524 -0.762)
			(end -1.524 -0.762)
			(stroke
				(width 0.1524)
				(type default)
			)
			(layer "B.SilkS")
		)
		(fp_line
			(start -1.1049 0.724916)
			(end -1.1049 -0.724916)
			(stroke
				(width 0.1)
				(type default)
			)
			(layer "B.Fab")
		)
		(fp_line
			(start 1.1049 0.724916)
			(end -1.1049 0.724916)
			(stroke
				(width 0.1)
				(type default)
			)
			(layer "B.Fab")
		)
		(fp_line
			(start -1.1049 -0.724916)
			(end 1.1049 -0.724916)
			(stroke
				(width 0.1)
				(type default)
			)
			(layer "B.Fab")
		)
		(fp_line
			(start 1.1049 -0.724916)
			(end 1.1049 0.724916)
			(stroke
				(width 0.1)
				(type default)
			)
			(layer "B.Fab")
		)
		(pad "1" smd rect
			(at 0.889 0 270)
			(size 1.016 1.27)
			(layers "B.Cu" "B.Mask" "B.Paste")
			(net "SW_P12V_AUX_PVDDCR_CPU0_P1_FLT")
		)
		(pad "2" smd rect
			(at -0.889 0 270)
			(size 1.016 1.27)
			(layers "B.Cu" "B.Mask" "B.Paste")
			(net "GND")
		)
	)
	(footprint ""
		(layer "B.Cu")
		(at 187.822078 -97.085912 -90)
		(property "Reference" "R262"
			(at 0 0 90)
			(layer "B.SilkS")
			(hide yes)
			(effects
				(font
					(size 1.27 1.27)
				)
				(justify mirror)
			)
		)
		(property "Value" ""
			(at 0 0 90)
			(layer "B.Fab")
			(effects
				(font
					(size 1.27 1.27)
				)
				(justify mirror)
			)
		)
		(duplicate_pad_numbers_are_jumpers no)
		(fp_line
			(start -0.7874 0.4064)
			(end 0.7874 0.4064)
			(stroke
				(width 0.1524)
				(type default)
			)
			(layer "B.SilkS")
		)
		(fp_line
			(start 0.7874 0.4064)
			(end 0.7874 -0.4064)
			(stroke
				(width 0.1524)
				(type default)
			)
			(layer "B.SilkS")
		)
		(fp_line
			(start -0.7874 -0.4064)
			(end -0.7874 0.4064)
			(stroke
				(width 0.1524)
				(type default)
			)
			(layer "B.SilkS")
		)
		(fp_line
			(start 0.7874 -0.4064)
			(end -0.7874 -0.4064)
			(stroke
				(width 0.1524)
				(type default)
			)
			(layer "B.SilkS")
		)
		(fp_line
			(start -0.67945 0.3048)
			(end -0.120396 0.3048)
			(stroke
				(width 0.1)
				(type default)
			)
			(layer "B.Fab")
		)
		(fp_line
			(start -0.120396 0.3048)
			(end -0.120396 0.2794)
			(stroke
				(width 0.1)
				(type default)
			)
			(layer "B.Fab")
		)
		(fp_line
			(start 0.12065 0.3048)
			(end 0.67945 0.3048)
			(stroke
				(width 0.1)
				(type default)
			)
			(layer "B.Fab")
		)
		(fp_line
			(start 0.67945 0.3048)
			(end 0.67945 -0.305054)
			(stroke
				(width 0.1)
				(type default)
			)
			(layer "B.Fab")
		)
		(fp_line
			(start -0.120396 0.2794)
			(end 0.12065 0.2794)
			(stroke
				(width 0.1)
				(type default)
			)
			(layer "B.Fab")
		)
		(fp_line
			(start 0.12065 0.2794)
			(end 0.12065 0.3048)
			(stroke
				(width 0.1)
				(type default)
			)
			(layer "B.Fab")
		)
		(fp_line
			(start -0.12065 -0.2794)
			(end -0.12065 -0.3048)
			(stroke
				(width 0.1)
				(type default)
			)
			(layer "B.Fab")
		)
		(fp_line
			(start 0.12065 -0.2794)
			(end -0.12065 -0.2794)
			(stroke
				(width 0.1)
				(type default)
			)
			(layer "B.Fab")
		)
		(fp_line
			(start -0.67945 -0.3048)
			(end -0.67945 0.3048)
			(stroke
				(width 0.1)
				(type default)
			)
			(layer "B.Fab")
		)
		(fp_line
			(start -0.12065 -0.3048)
			(end -0.67945 -0.3048)
			(stroke
				(width 0.1)
				(type default)
			)
			(layer "B.Fab")
		)
		(fp_line
			(start 0.12065 -0.305054)
			(end 0.12065 -0.2794)
			(stroke
				(width 0.1)
				(type default)
			)
			(layer "B.Fab")
		)
		(fp_line
			(start 0.67945 -0.305054)
			(end 0.12065 -0.305054)
			(stroke
				(width 0.1)
				(type default)
			)
			(layer "B.Fab")
		)
		(pad "1" smd circle
			(at 0.40005 0 90)
			(size 0 0)
			(layers "B.Cu" "B.Mask" "B.Paste")
			(net "CPU1_CORETYPE0")
		)
		(pad "2" smd circle
			(at -0.40005 0 90)
			(size 0 0)
			(layers "B.Cu" "B.Mask" "B.Paste")
			(net "FM_CPU1_CORETYPE0")
		)
	)
)
